(kicad_pcb
	(version 20260206)
	(generator "pcbnew")
	(generator_version "10.0")
	(general
		(thickness 1.6)
		(legacy_teardrops no)
	)
	(paper "A4")
	(title_block
		(title "04192023_DAF0TMB3IC0_F0TG_MB_C_brd_V02_OCP.brd")
		(comment 1 "Grand Teton / footprints 4570-4576 of 8354")
	)
	(layers
		(0 "F.Cu" signal "TOP")
		(4 "In1.Cu" signal "GND")
		(6 "In2.Cu" signal "IN1")
		(8 "In3.Cu" signal "GND1")
		(10 "In4.Cu" signal "IN2")
		(12 "In5.Cu" signal "GND2")
		(14 "In6.Cu" signal "IN3")
		(16 "In7.Cu" signal "GND3")
		(18 "In8.Cu" signal "VCC")
		(20 "In9.Cu" signal "VCC1")
		(22 "In10.Cu" signal "GND4")
		(24 "In11.Cu" signal "IN4")
		(26 "In12.Cu" signal "GND5")
		(28 "In13.Cu" signal "IN5")
		(30 "In14.Cu" signal "GND6")
		(32 "In15.Cu" signal "IN6")
		(34 "In16.Cu" signal "GND7")
		(2 "B.Cu" signal "BOTTOM")
		(9 "F.Adhes" user "F.Adhesive")
		(11 "B.Adhes" user "B.Adhesive")
		(13 "F.Paste" user "Package Geometry/Pastemask Top")
		(15 "B.Paste" user "Package Geometry/Pastemask Bottom")
		(5 "F.SilkS" user "Ref Des/Silkscreen Top")
		(7 "B.SilkS" user "Ref Des/Silkscreen Bottom")
		(1 "F.Mask" user "Board Geometry/Soldermask Top")
		(3 "B.Mask" user "Board Geometry/Soldermask Bottom")
		(17 "Dwgs.User" user "User.Drawings")
		(19 "Cmts.User" user "User.Comments")
		(21 "Eco1.User" user "User.Eco1")
		(23 "Eco2.User" user "User.Eco2")
		(25 "Edge.Cuts" user "Board Geometry/Outline")
		(27 "Margin" user)
		(31 "F.CrtYd" user "Package Geometry/Place Bound Top")
		(29 "B.CrtYd" user "Package Geometry/Place Bound Bottom")
		(35 "F.Fab" user "Ref Des/Assembly Top")
		(33 "B.Fab" user "Ref Des/Assembly Bottom")
	)
	(footprint ""
		(layer "F.Cu")
		(at 143.385286 -321.694556 -90)
		(property "Reference" "R570"
			(at 0 0 270)
			(layer "F.SilkS")
			(hide yes)
			(effects
				(font
					(size 1.27 1.27)
				)
			)
		)
		(property "Value" ""
			(at 0 0 270)
			(layer "F.Fab")
			(effects
				(font
					(size 1.27 1.27)
				)
			)
		)
		(duplicate_pad_numbers_are_jumpers no)
		(fp_line
			(start -0.7874 0.4064)
			(end -0.7874 -0.4064)
			(stroke
				(width 0.1524)
				(type default)
			)
			(layer "F.SilkS")
		)
		(fp_line
			(start 0.7874 0.4064)
			(end -0.7874 0.4064)
			(stroke
				(width 0.1524)
				(type default)
			)
			(layer "F.SilkS")
		)
		(fp_line
			(start -0.7874 -0.4064)
			(end 0.7874 -0.4064)
			(stroke
				(width 0.1524)
				(type default)
			)
			(layer "F.SilkS")
		)
		(fp_line
			(start 0.7874 -0.4064)
			(end 0.7874 0.4064)
			(stroke
				(width 0.1524)
				(type default)
			)
			(layer "F.SilkS")
		)
		(fp_line
			(start -0.67945 0.3048)
			(end -0.67945 -0.305054)
			(stroke
				(width 0.1)
				(type default)
			)
			(layer "F.Fab")
		)
		(fp_line
			(start -0.12065 0.3048)
			(end -0.67945 0.3048)
			(stroke
				(width 0.1)
				(type default)
			)
			(layer "F.Fab")
		)
		(fp_line
			(start 0.120396 0.3048)
			(end 0.120396 0.2794)
			(stroke
				(width 0.1)
				(type default)
			)
			(layer "F.Fab")
		)
		(fp_line
			(start 0.67945 0.3048)
			(end 0.120396 0.3048)
			(stroke
				(width 0.1)
				(type default)
			)
			(layer "F.Fab")
		)
		(fp_line
			(start -0.12065 0.2794)
			(end -0.12065 0.3048)
			(stroke
				(width 0.1)
				(type default)
			)
			(layer "F.Fab")
		)
		(fp_line
			(start 0.120396 0.2794)
			(end -0.12065 0.2794)
			(stroke
				(width 0.1)
				(type default)
			)
			(layer "F.Fab")
		)
		(fp_line
			(start -0.12065 -0.2794)
			(end 0.12065 -0.2794)
			(stroke
				(width 0.1)
				(type default)
			)
			(layer "F.Fab")
		)
		(fp_line
			(start 0.12065 -0.2794)
			(end 0.12065 -0.3048)
			(stroke
				(width 0.1)
				(type default)
			)
			(layer "F.Fab")
		)
		(fp_line
			(start 0.12065 -0.3048)
			(end 0.67945 -0.3048)
			(stroke
				(width 0.1)
				(type default)
			)
			(layer "F.Fab")
		)
		(fp_line
			(start 0.67945 -0.3048)
			(end 0.67945 0.3048)
			(stroke
				(width 0.1)
				(type default)
			)
			(layer "F.Fab")
		)
		(fp_line
			(start -0.67945 -0.305054)
			(end -0.12065 -0.305054)
			(stroke
				(width 0.1)
				(type default)
			)
			(layer "F.Fab")
		)
		(fp_line
			(start -0.12065 -0.305054)
			(end -0.12065 -0.2794)
			(stroke
				(width 0.1)
				(type default)
			)
			(layer "F.Fab")
		)
		(pad "1" smd circle
			(at -0.40005 0 270)
			(size 0 0)
			(layers "F.Cu" "F.Mask" "F.Paste")
			(net "CPU1_SPD_HOST_CTRL_N")
		)
		(pad "2" smd circle
			(at 0.40005 0 270)
			(size 0 0)
			(layers "F.Cu" "F.Mask" "F.Paste")
			(net "CPU1_SPD_HOST_CTRL_R_N")
		)
	)
	(footprint ""
		(layer "F.Cu")
		(at 229.5652 -152.954228 180)
		(property "Reference" "R6105"
			(at 0 0 180)
			(layer "F.SilkS")
			(hide yes)
			(effects
				(font
					(size 1.27 1.27)
				)
			)
		)
		(property "Value" ""
			(at 0 0 180)
			(layer "F.Fab")
			(effects
				(font
					(size 1.27 1.27)
				)
			)
		)
		(duplicate_pad_numbers_are_jumpers no)
		(fp_line
			(start 0.7874 0.4064)
			(end -0.7874 0.4064)
			(stroke
				(width 0.1524)
				(type default)
			)
			(layer "F.SilkS")
		)
		(fp_line
			(start 0.7874 -0.4064)
			(end 0.7874 0.4064)
			(stroke
				(width 0.1524)
				(type default)
			)
			(layer "F.SilkS")
		)
		(fp_line
			(start -0.7874 0.4064)
			(end -0.7874 -0.4064)
			(stroke
				(width 0.1524)
				(type default)
			)
			(layer "F.SilkS")
		)
		(fp_line
			(start -0.7874 -0.4064)
			(end 0.7874 -0.4064)
			(stroke
				(width 0.1524)
				(type default)
			)
			(layer "F.SilkS")
		)
		(fp_line
			(start 0.67945 0.3048)
			(end 0.120396 0.3048)
			(stroke
				(width 0.1)
				(type default)
			)
			(layer "F.Fab")
		)
		(fp_line
			(start 0.67945 -0.3048)
			(end 0.67945 0.3048)
			(stroke
				(width 0.1)
				(type default)
			)
			(layer "F.Fab")
		)
		(fp_line
			(start 0.12065 -0.2794)
			(end 0.12065 -0.3048)
			(stroke
				(width 0.1)
				(type default)
			)
			(layer "F.Fab")
		)
		(fp_line
			(start 0.12065 -0.3048)
			(end 0.67945 -0.3048)
			(stroke
				(width 0.1)
				(type default)
			)
			(layer "F.Fab")
		)
		(fp_line
			(start 0.120396 0.3048)
			(end 0.120396 0.2794)
			(stroke
				(width 0.1)
				(type default)
			)
			(layer "F.Fab")
		)
		(fp_line
			(start 0.120396 0.2794)
			(end -0.12065 0.2794)
			(stroke
				(width 0.1)
				(type default)
			)
			(layer "F.Fab")
		)
		(fp_line
			(start -0.12065 0.3048)
			(end -0.67945 0.3048)
			(stroke
				(width 0.1)
				(type default)
			)
			(layer "F.Fab")
		)
		(fp_line
			(start -0.12065 0.2794)
			(end -0.12065 0.3048)
			(stroke
				(width 0.1)
				(type default)
			)
			(layer "F.Fab")
		)
		(fp_line
			(start -0.12065 -0.2794)
			(end 0.12065 -0.2794)
			(stroke
				(width 0.1)
				(type default)
			)
			(layer "F.Fab")
		)
		(fp_line
			(start -0.12065 -0.305054)
			(end -0.12065 -0.2794)
			(stroke
				(width 0.1)
				(type default)
			)
			(layer "F.Fab")
		)
		(fp_line
			(start -0.67945 0.3048)
			(end -0.67945 -0.305054)
			(stroke
				(width 0.1)
				(type default)
			)
			(layer "F.Fab")
		)
		(fp_line
			(start -0.67945 -0.305054)
			(end -0.12065 -0.305054)
			(stroke
				(width 0.1)
				(type default)
			)
			(layer "F.Fab")
		)
		(pad "1" smd circle
			(at -0.40005 0 180)
			(size 0 0)
			(layers "F.Cu" "F.Mask" "F.Paste")
			(net "JTAG_CPU0_TDO_CPU1_TDI_R1")
		)
		(pad "2" smd circle
			(at 0.40005 0 180)
			(size 0 0)
			(layers "F.Cu" "F.Mask" "F.Paste")
			(net "JTAG_CPU0_TDO_CPU1_TDI")
		)
	)
	(footprint ""
		(layer "F.Cu")
		(at 449.443602 -429.25111)
		(property "Reference" "PR6608"
			(at 0 0 0)
			(layer "F.SilkS")
			(hide yes)
			(effects
				(font
					(size 1.27 1.27)
				)
			)
		)
		(property "Value" ""
			(at 0 0 0)
			(layer "F.Fab")
			(effects
				(font
					(size 1.27 1.27)
				)
			)
		)
		(duplicate_pad_numbers_are_jumpers no)
		(fp_line
			(start -0.7874 -0.4064)
			(end 0.7874 -0.4064)
			(stroke
				(width 0.1524)
				(type default)
			)
			(layer "F.SilkS")
		)
		(fp_line
			(start -0.7874 0.4064)
			(end -0.7874 -0.4064)
			(stroke
				(width 0.1524)
				(type default)
			)
			(layer "F.SilkS")
		)
		(fp_line
			(start 0.7874 -0.4064)
			(end 0.7874 0.4064)
			(stroke
				(width 0.1524)
				(type default)
			)
			(layer "F.SilkS")
		)
		(fp_line
			(start 0.7874 0.4064)
			(end -0.7874 0.4064)
			(stroke
				(width 0.1524)
				(type default)
			)
			(layer "F.SilkS")
		)
		(fp_line
			(start -0.67945 -0.305054)
			(end -0.12065 -0.305054)
			(stroke
				(width 0.1)
				(type default)
			)
			(layer "F.Fab")
		)
		(fp_line
			(start -0.67945 0.3048)
			(end -0.67945 -0.305054)
			(stroke
				(width 0.1)
				(type default)
			)
			(layer "F.Fab")
		)
		(fp_line
			(start -0.12065 -0.305054)
			(end -0.12065 -0.2794)
			(stroke
				(width 0.1)
				(type default)
			)
			(layer "F.Fab")
		)
		(fp_line
			(start -0.12065 -0.2794)
			(end 0.12065 -0.2794)
			(stroke
				(width 0.1)
				(type default)
			)
			(layer "F.Fab")
		)
		(fp_line
			(start -0.12065 0.2794)
			(end -0.12065 0.3048)
			(stroke
				(width 0.1)
				(type default)
			)
			(layer "F.Fab")
		)
		(fp_line
			(start -0.12065 0.3048)
			(end -0.67945 0.3048)
			(stroke
				(width 0.1)
				(type default)
			)
			(layer "F.Fab")
		)
		(fp_line
			(start 0.120396 0.2794)
			(end -0.12065 0.2794)
			(stroke
				(width 0.1)
				(type default)
			)
			(layer "F.Fab")
		)
		(fp_line
			(start 0.120396 0.3048)
			(end 0.120396 0.2794)
			(stroke
				(width 0.1)
				(type default)
			)
			(layer "F.Fab")
		)
		(fp_line
			(start 0.12065 -0.3048)
			(end 0.67945 -0.3048)
			(stroke
				(width 0.1)
				(type default)
			)
			(layer "F.Fab")
		)
		(fp_line
			(start 0.12065 -0.2794)
			(end 0.12065 -0.3048)
			(stroke
				(width 0.1)
				(type default)
			)
			(layer "F.Fab")
		)
		(fp_line
			(start 0.67945 -0.3048)
			(end 0.67945 0.3048)
			(stroke
				(width 0.1)
				(type default)
			)
			(layer "F.Fab")
		)
		(fp_line
			(start 0.67945 0.3048)
			(end 0.120396 0.3048)
			(stroke
				(width 0.1)
				(type default)
			)
			(layer "F.Fab")
		)
		(pad "1" smd circle
			(at -0.40005 0)
			(size 0 0)
			(layers "F.Cu" "F.Mask" "F.Paste")
			(net "P0V9_RETIMER_CPU0_VCC")
		)
		(pad "2" smd circle
			(at 0.40005 0)
			(size 0 0)
			(layers "F.Cu" "F.Mask" "F.Paste")
			(net "P3V3_AUX")
		)
	)
	(footprint ""
		(layer "F.Cu")
		(at 302.133 -365.125 180)
		(property "Reference" "C5013"
			(at 0 0 180)
			(layer "F.SilkS")
			(hide yes)
			(effects
				(font
					(size 1.27 1.27)
				)
			)
		)
		(property "Value" ""
			(at 0 0 180)
			(layer "F.Fab")
			(effects
				(font
					(size 1.27 1.27)
				)
			)
		)
		(duplicate_pad_numbers_are_jumpers no)
		(fp_line
			(start 0.7874 0.4064)
			(end -0.7874 0.4064)
			(stroke
				(width 0.1524)
				(type default)
			)
			(layer "F.SilkS")
		)
		(fp_line
			(start 0.7874 -0.4064)
			(end 0.7874 0.4064)
			(stroke
				(width 0.1524)
				(type default)
			)
			(layer "F.SilkS")
		)
		(fp_line
			(start -0.7874 0.4064)
			(end -0.7874 -0.4064)
			(stroke
				(width 0.1524)
				(type default)
			)
			(layer "F.SilkS")
		)
		(fp_line
			(start -0.7874 -0.4064)
			(end 0.7874 -0.4064)
			(stroke
				(width 0.1524)
				(type default)
			)
			(layer "F.SilkS")
		)
		(fp_line
			(start 0.67945 0.3048)
			(end 0.120396 0.3048)
			(stroke
				(width 0.1)
				(type default)
			)
			(layer "F.Fab")
		)
		(fp_line
			(start 0.67945 -0.3048)
			(end 0.67945 0.3048)
			(stroke
				(width 0.1)
				(type default)
			)
			(layer "F.Fab")
		)
		(fp_line
			(start 0.12065 -0.2794)
			(end 0.12065 -0.3048)
			(stroke
				(width 0.1)
				(type default)
			)
			(layer "F.Fab")
		)
		(fp_line
			(start 0.12065 -0.3048)
			(end 0.67945 -0.3048)
			(stroke
				(width 0.1)
				(type default)
			)
			(layer "F.Fab")
		)
		(fp_line
			(start 0.120396 0.3048)
			(end 0.120396 0.2794)
			(stroke
				(width 0.1)
				(type default)
			)
			(layer "F.Fab")
		)
		(fp_line
			(start 0.120396 0.2794)
			(end -0.12065 0.2794)
			(stroke
				(width 0.1)
				(type default)
			)
			(layer "F.Fab")
		)
		(fp_line
			(start -0.12065 0.3048)
			(end -0.67945 0.3048)
			(stroke
				(width 0.1)
				(type default)
			)
			(layer "F.Fab")
		)
		(fp_line
			(start -0.12065 0.2794)
			(end -0.12065 0.3048)
			(stroke
				(width 0.1)
				(type default)
			)
			(layer "F.Fab")
		)
		(fp_line
			(start -0.12065 -0.2794)
			(end 0.12065 -0.2794)
			(stroke
				(width 0.1)
				(type default)
			)
			(layer "F.Fab")
		)
		(fp_line
			(start -0.12065 -0.305054)
			(end -0.12065 -0.2794)
			(stroke
				(width 0.1)
				(type default)
			)
			(layer "F.Fab")
		)
		(fp_line
			(start -0.67945 0.3048)
			(end -0.67945 -0.305054)
			(stroke
				(width 0.1)
				(type default)
			)
			(layer "F.Fab")
		)
		(fp_line
			(start -0.67945 -0.305054)
			(end -0.12065 -0.305054)
			(stroke
				(width 0.1)
				(type default)
			)
			(layer "F.Fab")
		)
		(pad "1" smd circle
			(at -0.40005 0 180)
			(size 0 0)
			(layers "F.Cu" "F.Mask" "F.Paste")
			(net "PVDDCR_CPU1_P0_SMB_ALERT")
		)
		(pad "2" smd circle
			(at 0.40005 0 180)
			(size 0 0)
			(layers "F.Cu" "F.Mask" "F.Paste")
			(net "GND")
		)
	)
	(footprint ""
		(layer "F.Cu")
		(at 166.116 -99.06)
		(property "Reference" "R1144"
			(at 0 0 0)
			(layer "F.SilkS")
			(hide yes)
			(effects
				(font
					(size 1.27 1.27)
				)
			)
		)
		(property "Value" ""
			(at 0 0 0)
			(layer "F.Fab")
			(effects
				(font
					(size 1.27 1.27)
				)
			)
		)
		(duplicate_pad_numbers_are_jumpers no)
		(fp_line
			(start -0.7874 -0.4064)
			(end 0.7874 -0.4064)
			(stroke
				(width 0.1524)
				(type default)
			)
			(layer "F.SilkS")
		)
		(fp_line
			(start -0.7874 0.4064)
			(end -0.7874 -0.4064)
			(stroke
				(width 0.1524)
				(type default)
			)
			(layer "F.SilkS")
		)
		(fp_line
			(start 0.7874 -0.4064)
			(end 0.7874 0.4064)
			(stroke
				(width 0.1524)
				(type default)
			)
			(layer "F.SilkS")
		)
		(fp_line
			(start 0.7874 0.4064)
			(end -0.7874 0.4064)
			(stroke
				(width 0.1524)
				(type default)
			)
			(layer "F.SilkS")
		)
		(fp_line
			(start -0.67945 -0.305054)
			(end -0.12065 -0.305054)
			(stroke
				(width 0.1)
				(type default)
			)
			(layer "F.Fab")
		)
		(fp_line
			(start -0.67945 0.3048)
			(end -0.67945 -0.305054)
			(stroke
				(width 0.1)
				(type default)
			)
			(layer "F.Fab")
		)
		(fp_line
			(start -0.12065 -0.305054)
			(end -0.12065 -0.2794)
			(stroke
				(width 0.1)
				(type default)
			)
			(layer "F.Fab")
		)
		(fp_line
			(start -0.12065 -0.2794)
			(end 0.12065 -0.2794)
			(stroke
				(width 0.1)
				(type default)
			)
			(layer "F.Fab")
		)
		(fp_line
			(start -0.12065 0.2794)
			(end -0.12065 0.3048)
			(stroke
				(width 0.1)
				(type default)
			)
			(layer "F.Fab")
		)
		(fp_line
			(start -0.12065 0.3048)
			(end -0.67945 0.3048)
			(stroke
				(width 0.1)
				(type default)
			)
			(layer "F.Fab")
		)
		(fp_line
			(start 0.120396 0.2794)
			(end -0.12065 0.2794)
			(stroke
				(width 0.1)
				(type default)
			)
			(layer "F.Fab")
		)
		(fp_line
			(start 0.120396 0.3048)
			(end 0.120396 0.2794)
			(stroke
				(width 0.1)
				(type default)
			)
			(layer "F.Fab")
		)
		(fp_line
			(start 0.12065 -0.3048)
			(end 0.67945 -0.3048)
			(stroke
				(width 0.1)
				(type default)
			)
			(layer "F.Fab")
		)
		(fp_line
			(start 0.12065 -0.2794)
			(end 0.12065 -0.3048)
			(stroke
				(width 0.1)
				(type default)
			)
			(layer "F.Fab")
		)
		(fp_line
			(start 0.67945 -0.3048)
			(end 0.67945 0.3048)
			(stroke
				(width 0.1)
				(type default)
			)
			(layer "F.Fab")
		)
		(fp_line
			(start 0.67945 0.3048)
			(end 0.120396 0.3048)
			(stroke
				(width 0.1)
				(type default)
			)
			(layer "F.Fab")
		)
		(pad "1" smd circle
			(at -0.40005 0)
			(size 0 0)
			(layers "F.Cu" "F.Mask" "F.Paste")
			(net "P3V3_AUX")
		)
		(pad "2" smd circle
			(at 0.40005 0)
			(size 0 0)
			(layers "F.Cu" "F.Mask" "F.Paste")
			(net "OCP_V3_1_P3V3_PLD_R_PWRGD")
		)
	)
	(footprint ""
		(layer "F.Cu")
		(at 103.998522 -31.788354 -90)
		(property "Reference" "R345"
			(at 0 0 270)
			(layer "F.SilkS")
			(hide yes)
			(effects
				(font
					(size 1.27 1.27)
				)
			)
		)
		(property "Value" ""
			(at 0 0 270)
			(layer "F.Fab")
			(effects
				(font
					(size 1.27 1.27)
				)
			)
		)
		(duplicate_pad_numbers_are_jumpers no)
		(fp_line
			(start -0.32512 0.175006)
			(end -0.32512 -0.175006)
			(stroke
				(width 0.1)
				(type default)
			)
			(layer "F.Fab")
		)
		(fp_line
			(start 0.32512 0.175006)
			(end -0.32512 0.175006)
			(stroke
				(width 0.1)
				(type default)
			)
			(layer "F.Fab")
		)
		(fp_line
			(start -0.32512 -0.175006)
			(end 0.32512 -0.175006)
			(stroke
				(width 0.1)
				(type default)
			)
			(layer "F.Fab")
		)
		(fp_line
			(start 0.32512 -0.175006)
			(end 0.32512 0.175006)
			(stroke
				(width 0.1)
				(type default)
			)
			(layer "F.Fab")
		)
		(pad "1" smd rect
			(at -0.2667 0 270)
			(size 0.3048 0.381)
			(layers "F.Cu" "F.Mask" "F.Paste")
			(net "USB2_CPU0_P0_R2_DN")
		)
		(pad "2" smd rect
			(at 0.2667 0 90)
			(size 0.3048 0.381)
			(layers "F.Cu" "F.Mask" "F.Paste")
			(net "GND")
		)
	)
	(footprint ""
		(layer "F.Cu")
		(at 164.927026 -58.06821 90)
		(property "Reference" "R3634"
			(at 4.77012 -1.859026 0)
			(unlocked yes)
			(layer "F.SilkS")
			(effects
				(font
					(size 0.7874 0.5842)
					(thickness 0.1524)
				)
				(justify left)
			)
		)
		(property "Value" ""
			(at 0 0 90)
			(layer "F.Fab")
			(effects
				(font
					(size 1.27 1.27)
				)
			)
		)
		(duplicate_pad_numbers_are_jumpers no)
		(fp_line
			(start 3.937508 -1.8796)
			(end -3.937508 -1.8796)
			(stroke
				(width 0.1524)
				(type default)
			)
			(layer "F.SilkS")
		)
		(fp_line
			(start -3.937508 -1.8796)
			(end -3.937508 1.8796)
			(stroke
				(width 0.1524)
				(type default)
			)
			(layer "F.SilkS")
		)
		(fp_line
			(start 3.937508 1.8796)
			(end 3.937508 -1.8796)
			(stroke
				(width 0.1524)
				(type default)
			)
			(layer "F.SilkS")
		)
		(fp_line
			(start -3.937508 1.8796)
			(end 3.937508 1.8796)
			(stroke
				(width 0.1524)
				(type default)
			)
			(layer "F.SilkS")
		)
		(fp_line
			(start 3.275076 -1.674876)
			(end -3.275076 -1.674876)
			(stroke
				(width 0.1)
				(type default)
			)
			(layer "F.Fab")
		)
		(fp_line
			(start -3.275076 -1.674876)
			(end -3.275076 1.674876)
			(stroke
				(width 0.1)
				(type default)
			)
			(layer "F.Fab")
		)
		(fp_line
			(start 3.275076 1.674876)
			(end 3.275076 -1.674876)
			(stroke
				(width 0.1)
				(type default)
			)
			(layer "F.Fab")
		)
		(fp_line
			(start -3.275076 1.674876)
			(end 3.275076 1.674876)
			(stroke
				(width 0.1)
				(type default)
			)
			(layer "F.Fab")
		)
		(pad "1" smd rect
			(at -2.350008 0 90)
			(size 2.921 3.5052)
			(layers "F.Cu" "F.Mask" "F.Paste")
			(net "P3V3_M2_0")
		)
		(pad "2" smd rect
			(at 2.350008 0 90)
			(size 2.921 3.5052)
			(layers "F.Cu" "F.Mask" "F.Paste")
			(net "P3V3")
		)
	)
)
